(kicad_pcb
	(version 20260206)
	(generator "pcbnew")
	(generator_version "10.0")
	(general
		(thickness 1.6)
		(legacy_teardrops no)
	)
	(paper "A4")
	(title_block
		(title "panther-plus-userver — 13130-1b_20150205.brd")
		(comment 1 "Honey Badger (Wiwynn) / footprint 894 of 1509 (DIMM1), pads 156-162 of 210")
	)
	(layers
		(0 "F.Cu" signal "TOP")
		(4 "In1.Cu" signal "L2")
		(6 "In2.Cu" signal "L3")
		(8 "In3.Cu" signal "L4")
		(10 "In4.Cu" signal "L5")
		(12 "In5.Cu" signal "L6")
		(14 "In6.Cu" signal "L7")
		(16 "In7.Cu" signal "L8")
		(18 "In8.Cu" signal "L9")
		(20 "In9.Cu" signal "L10")
		(22 "In10.Cu" signal "L11")
		(2 "B.Cu" signal "BOTTOM")
		(9 "F.Adhes" user "F.Adhesive")
		(11 "B.Adhes" user "B.Adhesive")
		(13 "F.Paste" user "Package Geometry/Pastemask Top")
		(15 "B.Paste" user "Package Geometry/Pastemask Bottom")
		(5 "F.SilkS" user "Ref Des/Silkscreen Top")
		(7 "B.SilkS" user "Ref Des/Silkscreen Bottom")
		(1 "F.Mask" user "Board Geometry/Soldermask Top")
		(3 "B.Mask" user "Board Geometry/Soldermask Bottom")
		(17 "Dwgs.User" user "User.Drawings")
		(19 "Cmts.User" user "User.Comments")
		(21 "Eco1.User" user "User.Eco1")
		(23 "Eco2.User" user "User.Eco2")
		(25 "Edge.Cuts" user "Board Geometry/Outline")
		(27 "Margin" user)
		(31 "F.CrtYd" user "Package Geometry/Place Bound Top")
		(29 "B.CrtYd" user "Package Geometry/Place Bound Bottom")
		(35 "F.Fab" user "Ref Des/Assembly Top")
		(33 "B.Fab" user "Ref Des/Assembly Bottom")
	)
	(footprint ""
		(layer "B.Cu")
		(at 158.500064 -66.699892 180)
		(property "Reference" "DIMM1"
			(at 0 0 0)
			(layer "B.SilkS")
			(hide yes)
			(effects
				(font
					(size 1.27 1.27)
				)
				(justify mirror)
			)
		)
		(property "Value" "DDR3-204P-142-COLAY-1-GP-U"
			(at 41.312338 -16.676878 180)
			(unlocked yes)
			(layer "B.Fab")
			(hide yes)
			(effects
				(font
					(size 1.016 1.016)
					(thickness 0.1524)
				)
				(justify mirror)
			)
		)
		(property "Device Type" "AS0A626-J8R6-7H-COLAY-1"
			(at 41.312338 -18.200878 180)
			(unlocked yes)
			(layer "B.Fab")
			(hide yes)
			(effects
				(font
					(size 1.016 1.016)
					(thickness 0.1524)
				)
				(justify mirror)
			)
		)
		(duplicate_pad_numbers_are_jumpers no)
		(pad "154" smd custom
			(at 16.649954 4.100068)
			(size 0.1143 0.1143)
			(layers "B.Cu" "B.Mask" "B.Paste")
			(net "M_A_DQS_DN5")
			(options
				(clearance outline)
				(anchor circle)
			)
			(primitives
				(gr_poly
					(pts
						(xy 0 -0.9017) (xy -0.03175 -0.89916) (xy -0.0635 -0.889) (xy -0.09144 -0.87376) (xy -0.11684 -0.85344)
						(xy -0.13716 -0.82804) (xy -0.1524 -0.8001) (xy -0.16256 -0.76835) (xy -0.1651 -0.7366) (xy -0.1651 0.13462)
						(xy -0.17272 0.14224) (xy -0.19812 0.1778) (xy -0.2032 0.18796) (xy -0.20701 0.19685) (xy -0.21209 0.20701)
						(xy -0.2159 0.21717) (xy -0.21844 0.22733) (xy -0.22225 0.23876) (xy -0.22352 0.24892) (xy -0.22606 0.25908)
						(xy -0.22733 0.27051) (xy -0.22733 0.28067) (xy -0.2286 0.2921) (xy -0.22733 0.30353) (xy -0.22733 0.31369)
						(xy -0.22606 0.32512) (xy -0.22352 0.33528) (xy -0.22225 0.34544) (xy -0.21844 0.35687) (xy -0.2159 0.36703)
						(xy -0.21209 0.37719) (xy -0.20701 0.38735) (xy -0.2032 0.39624) (xy -0.19812 0.4064) (xy -0.17272 0.44196)
						(xy -0.1651 0.44958) (xy -0.1651 0.7366) (xy -0.16256 0.76835) (xy -0.1524 0.8001) (xy -0.13716 0.82804)
						(xy -0.11684 0.85344) (xy -0.09144 0.87376) (xy -0.0635 0.889) (xy -0.03175 0.89916) (xy 0 0.9017)
						(xy 0.03175 0.89916) (xy 0.0635 0.889) (xy 0.09144 0.87376) (xy 0.11684 0.85344) (xy 0.13716 0.82804)
						(xy 0.1524 0.8001) (xy 0.16256 0.76835) (xy 0.1651 0.7366) (xy 0.1651 0.44958) (xy 0.17272 0.44196)
						(xy 0.19812 0.4064) (xy 0.2032 0.39624) (xy 0.20701 0.38735) (xy 0.21209 0.37719) (xy 0.2159 0.36703)
						(xy 0.21844 0.35687) (xy 0.22225 0.34544) (xy 0.22352 0.33528) (xy 0.22606 0.32512) (xy 0.22733 0.31369)
						(xy 0.22733 0.30353) (xy 0.2286 0.2921) (xy 0.22733 0.28067) (xy 0.22733 0.27051) (xy 0.22606 0.25908)
						(xy 0.22352 0.24892) (xy 0.22225 0.23876) (xy 0.21844 0.22733) (xy 0.2159 0.21717) (xy 0.21209 0.20701)
						(xy 0.20701 0.19685) (xy 0.2032 0.18796) (xy 0.19812 0.1778) (xy 0.17272 0.14224) (xy 0.1651 0.13462)
						(xy 0.1651 -0.7366) (xy 0.16256 -0.76835) (xy 0.1524 -0.8001) (xy 0.13716 -0.82804) (xy 0.11684 -0.85344)
						(xy 0.09144 -0.87376) (xy 0.0635 -0.889) (xy 0.03175 -0.89916)
					)
					(width 0)
					(fill yes)
				)
			)
		)
		(pad "155" smd custom
			(at 16.949928 -4.100068)
			(size 0.1143 0.1143)
			(layers "B.Cu" "B.Mask" "B.Paste")
			(net "GND")
			(options
				(clearance outline)
				(anchor circle)
			)
			(primitives
				(gr_poly
					(pts
						(xy 0 -0.9017) (xy -0.03175 -0.89916) (xy -0.0635 -0.889) (xy -0.09144 -0.87376) (xy -0.11684 -0.85344)
						(xy -0.13716 -0.82804) (xy -0.1524 -0.8001) (xy -0.16256 -0.76835) (xy -0.1651 -0.7366) (xy -0.1651 -0.19685)
						(xy -0.17272 -0.18923) (xy -0.17907 -0.18034) (xy -0.18669 -0.17145) (xy -0.19177 -0.16256) (xy -0.19812 -0.15367)
						(xy -0.20828 -0.13335) (xy -0.21971 -0.10287) (xy -0.22225 -0.09271) (xy -0.22479 -0.08128) (xy -0.22606 -0.07112)
						(xy -0.2286 -0.05969) (xy -0.2286 -0.01651) (xy -0.22606 -0.00508) (xy -0.22479 0.00508) (xy -0.22225 0.01651)
						(xy -0.21971 0.02667) (xy -0.20828 0.05715) (xy -0.19812 0.07747) (xy -0.19177 0.08636) (xy -0.18669 0.09525)
						(xy -0.17907 0.10414) (xy -0.17272 0.11303) (xy -0.1651 0.12065) (xy -0.1651 0.7366) (xy -0.16256 0.76835)
						(xy -0.1524 0.8001) (xy -0.13716 0.82804) (xy -0.11684 0.85344) (xy -0.09144 0.87376) (xy -0.0635 0.889)
						(xy -0.03175 0.89916) (xy 0 0.9017) (xy 0.03175 0.89916) (xy 0.0635 0.889) (xy 0.09144 0.87376)
						(xy 0.11684 0.85344) (xy 0.13716 0.82804) (xy 0.1524 0.8001) (xy 0.16256 0.76835) (xy 0.1651 0.7366)
						(xy 0.1651 0.11938) (xy 0.17272 0.11176) (xy 0.19812 0.0762) (xy 0.2032 0.06604) (xy 0.20701 0.05715)
						(xy 0.21209 0.04699) (xy 0.2159 0.03683) (xy 0.21844 0.02667) (xy 0.22225 0.01524) (xy 0.22352 0.00508)
						(xy 0.22606 -0.00508) (xy 0.22733 -0.01651) (xy 0.22733 -0.02667) (xy 0.2286 -0.0381) (xy 0.22733 -0.04953)
						(xy 0.22733 -0.05969) (xy 0.22606 -0.07112) (xy 0.22352 -0.08128) (xy 0.22225 -0.09144) (xy 0.21844 -0.10287)
						(xy 0.2159 -0.11303) (xy 0.21209 -0.12319) (xy 0.20701 -0.13335) (xy 0.2032 -0.14224) (xy 0.19812 -0.1524)
						(xy 0.17272 -0.18796) (xy 0.1651 -0.19558) (xy 0.1651 -0.7366) (xy 0.16256 -0.76835) (xy 0.1524 -0.8001)
						(xy 0.13716 -0.82804) (xy 0.11684 -0.85344) (xy 0.09144 -0.87376) (xy 0.0635 -0.889) (xy 0.03175 -0.89916)
					)
					(width 0)
					(fill yes)
				)
			)
		)
		(pad "156" smd custom
			(at 17.249902 4.100068)
			(size 0.1143 0.1143)
			(layers "B.Cu" "B.Mask" "B.Paste")
			(net "M_A_DQS_DP5")
			(options
				(clearance outline)
				(anchor circle)
			)
			(primitives
				(gr_poly
					(pts
						(xy 0 -0.9017) (xy -0.03175 -0.89916) (xy -0.0635 -0.889) (xy -0.09144 -0.87376) (xy -0.11684 -0.85344)
						(xy -0.13716 -0.82804) (xy -0.1524 -0.8001) (xy -0.16256 -0.76835) (xy -0.1651 -0.7366) (xy -0.1651 -0.11938)
						(xy -0.17272 -0.11176) (xy -0.19812 -0.0762) (xy -0.2032 -0.06604) (xy -0.20701 -0.05715) (xy -0.21209 -0.04699)
						(xy -0.2159 -0.03683) (xy -0.21844 -0.02667) (xy -0.22225 -0.01524) (xy -0.22352 -0.00508) (xy -0.22606 0.00508)
						(xy -0.22733 0.01651) (xy -0.22733 0.02667) (xy -0.2286 0.0381) (xy -0.22733 0.04953) (xy -0.22733 0.05969)
						(xy -0.22606 0.07112) (xy -0.22352 0.08128) (xy -0.22225 0.09144) (xy -0.21844 0.10287) (xy -0.2159 0.11303)
						(xy -0.21209 0.12319) (xy -0.20701 0.13335) (xy -0.2032 0.14224) (xy -0.19812 0.1524) (xy -0.17272 0.18796)
						(xy -0.1651 0.19558) (xy -0.1651 0.7366) (xy -0.16256 0.76835) (xy -0.1524 0.8001) (xy -0.13716 0.82804)
						(xy -0.11684 0.85344) (xy -0.09144 0.87376) (xy -0.0635 0.889) (xy -0.03175 0.89916) (xy 0 0.9017)
						(xy 0.03175 0.89916) (xy 0.0635 0.889) (xy 0.09144 0.87376) (xy 0.11684 0.85344) (xy 0.13716 0.82804)
						(xy 0.1524 0.8001) (xy 0.16256 0.76835) (xy 0.1651 0.7366) (xy 0.1651 0.19685) (xy 0.17272 0.18923)
						(xy 0.17907 0.18034) (xy 0.18669 0.17145) (xy 0.19177 0.16256) (xy 0.19812 0.15367) (xy 0.20828 0.13335)
						(xy 0.21971 0.10287) (xy 0.22225 0.09271) (xy 0.22479 0.08128) (xy 0.22606 0.07112) (xy 0.2286 0.05969)
						(xy 0.2286 0.01651) (xy 0.22606 0.00508) (xy 0.22479 -0.00508) (xy 0.22225 -0.01651) (xy 0.21971 -0.02667)
						(xy 0.20828 -0.05715) (xy 0.19812 -0.07747) (xy 0.19177 -0.08636) (xy 0.18669 -0.09525) (xy 0.17907 -0.10414)
						(xy 0.17272 -0.11303) (xy 0.1651 -0.12065) (xy 0.1651 -0.7366) (xy 0.16256 -0.76835) (xy 0.1524 -0.8001)
						(xy 0.13716 -0.82804) (xy 0.11684 -0.85344) (xy 0.09144 -0.87376) (xy 0.0635 -0.889) (xy 0.03175 -0.89916)
					)
					(width 0)
					(fill yes)
				)
			)
		)
		(pad "157" smd custom
			(at 17.549876 -4.100068)
			(size 0.1143 0.1143)
			(layers "B.Cu" "B.Mask" "B.Paste")
			(net "GND")
			(options
				(clearance outline)
				(anchor circle)
			)
			(primitives
				(gr_poly
					(pts
						(xy 0 -0.9017) (xy -0.03175 -0.89916) (xy -0.0635 -0.889) (xy -0.09144 -0.87376) (xy -0.11684 -0.85344)
						(xy -0.13716 -0.82804) (xy -0.1524 -0.8001) (xy -0.16256 -0.76835) (xy -0.1651 -0.7366) (xy -0.1651 -0.44958)
						(xy -0.17272 -0.44196) (xy -0.19812 -0.4064) (xy -0.2032 -0.39624) (xy -0.20701 -0.38735) (xy -0.21209 -0.37719)
						(xy -0.2159 -0.36703) (xy -0.21844 -0.35687) (xy -0.22225 -0.34544) (xy -0.22352 -0.33528) (xy -0.22606 -0.32512)
						(xy -0.22733 -0.31369) (xy -0.22733 -0.30353) (xy -0.2286 -0.2921) (xy -0.22733 -0.28067) (xy -0.22733 -0.27051)
						(xy -0.22606 -0.25908) (xy -0.22352 -0.24892) (xy -0.22225 -0.23876) (xy -0.21844 -0.22733) (xy -0.2159 -0.21717)
						(xy -0.21209 -0.20701) (xy -0.20701 -0.19685) (xy -0.2032 -0.18796) (xy -0.19812 -0.1778) (xy -0.17272 -0.14224)
						(xy -0.1651 -0.13462) (xy -0.1651 0.7366) (xy -0.16256 0.76835) (xy -0.1524 0.8001) (xy -0.13716 0.82804)
						(xy -0.11684 0.85344) (xy -0.09144 0.87376) (xy -0.0635 0.889) (xy -0.03175 0.89916) (xy 0 0.9017)
						(xy 0.03175 0.89916) (xy 0.0635 0.889) (xy 0.09144 0.87376) (xy 0.11684 0.85344) (xy 0.13716 0.82804)
						(xy 0.1524 0.8001) (xy 0.16256 0.76835) (xy 0.1651 0.7366) (xy 0.1651 -0.13462) (xy 0.17272 -0.14224)
						(xy 0.19812 -0.1778) (xy 0.2032 -0.18796) (xy 0.20701 -0.19685) (xy 0.21209 -0.20701) (xy 0.2159 -0.21717)
						(xy 0.21844 -0.22733) (xy 0.22225 -0.23876) (xy 0.22352 -0.24892) (xy 0.22606 -0.25908) (xy 0.22733 -0.27051)
						(xy 0.22733 -0.28067) (xy 0.2286 -0.2921) (xy 0.22733 -0.30353) (xy 0.22733 -0.31369) (xy 0.22606 -0.32512)
						(xy 0.22352 -0.33528) (xy 0.22225 -0.34544) (xy 0.21844 -0.35687) (xy 0.2159 -0.36703) (xy 0.21209 -0.37719)
						(xy 0.20701 -0.38735) (xy 0.2032 -0.39624) (xy 0.19812 -0.4064) (xy 0.17272 -0.44196) (xy 0.1651 -0.44958)
						(xy 0.1651 -0.7366) (xy 0.16256 -0.76835) (xy 0.1524 -0.8001) (xy 0.13716 -0.82804) (xy 0.11684 -0.85344)
						(xy 0.09144 -0.87376) (xy 0.0635 -0.889) (xy 0.03175 -0.89916)
					)
					(width 0)
					(fill yes)
				)
			)
		)
		(pad "158" smd custom
			(at 17.850104 4.100068)
			(size 0.1143 0.1143)
			(layers "B.Cu" "B.Mask" "B.Paste")
			(net "GND")
			(options
				(clearance outline)
				(anchor circle)
			)
			(primitives
				(gr_poly
					(pts
						(xy 0 -0.9017) (xy -0.03175 -0.89916) (xy -0.0635 -0.889) (xy -0.09144 -0.87376) (xy -0.11684 -0.85344)
						(xy -0.13716 -0.82804) (xy -0.1524 -0.8001) (xy -0.16256 -0.76835) (xy -0.1651 -0.7366) (xy -0.1651 0.13462)
						(xy -0.17272 0.14224) (xy -0.19812 0.1778) (xy -0.2032 0.18796) (xy -0.20701 0.19685) (xy -0.21209 0.20701)
						(xy -0.2159 0.21717) (xy -0.21844 0.22733) (xy -0.22225 0.23876) (xy -0.22352 0.24892) (xy -0.22606 0.25908)
						(xy -0.22733 0.27051) (xy -0.22733 0.28067) (xy -0.2286 0.2921) (xy -0.22733 0.30353) (xy -0.22733 0.31369)
						(xy -0.22606 0.32512) (xy -0.22352 0.33528) (xy -0.22225 0.34544) (xy -0.21844 0.35687) (xy -0.2159 0.36703)
						(xy -0.21209 0.37719) (xy -0.20701 0.38735) (xy -0.2032 0.39624) (xy -0.19812 0.4064) (xy -0.17272 0.44196)
						(xy -0.1651 0.44958) (xy -0.1651 0.7366) (xy -0.16256 0.76835) (xy -0.1524 0.8001) (xy -0.13716 0.82804)
						(xy -0.11684 0.85344) (xy -0.09144 0.87376) (xy -0.0635 0.889) (xy -0.03175 0.89916) (xy 0 0.9017)
						(xy 0.03175 0.89916) (xy 0.0635 0.889) (xy 0.09144 0.87376) (xy 0.11684 0.85344) (xy 0.13716 0.82804)
						(xy 0.1524 0.8001) (xy 0.16256 0.76835) (xy 0.1651 0.7366) (xy 0.1651 0.44958) (xy 0.17272 0.44196)
						(xy 0.19812 0.4064) (xy 0.2032 0.39624) (xy 0.20701 0.38735) (xy 0.21209 0.37719) (xy 0.2159 0.36703)
						(xy 0.21844 0.35687) (xy 0.22225 0.34544) (xy 0.22352 0.33528) (xy 0.22606 0.32512) (xy 0.22733 0.31369)
						(xy 0.22733 0.30353) (xy 0.2286 0.2921) (xy 0.22733 0.28067) (xy 0.22733 0.27051) (xy 0.22606 0.25908)
						(xy 0.22352 0.24892) (xy 0.22225 0.23876) (xy 0.21844 0.22733) (xy 0.2159 0.21717) (xy 0.21209 0.20701)
						(xy 0.20701 0.19685) (xy 0.2032 0.18796) (xy 0.19812 0.1778) (xy 0.17272 0.14224) (xy 0.1651 0.13462)
						(xy 0.1651 -0.7366) (xy 0.16256 -0.76835) (xy 0.1524 -0.8001) (xy 0.13716 -0.82804) (xy 0.11684 -0.85344)
						(xy 0.09144 -0.87376) (xy 0.0635 -0.889) (xy 0.03175 -0.89916)
					)
					(width 0)
					(fill yes)
				)
			)
		)
		(pad "159" smd custom
			(at 18.150078 -4.100068)
			(size 0.1143 0.1143)
			(layers "B.Cu" "B.Mask" "B.Paste")
			(net "M_A_DQ42")
			(options
				(clearance outline)
				(anchor circle)
			)
			(primitives
				(gr_poly
					(pts
						(xy 0 -0.9017) (xy -0.03175 -0.89916) (xy -0.0635 -0.889) (xy -0.09144 -0.87376) (xy -0.11684 -0.85344)
						(xy -0.13716 -0.82804) (xy -0.1524 -0.8001) (xy -0.16256 -0.76835) (xy -0.1651 -0.7366) (xy -0.1651 -0.19685)
						(xy -0.17272 -0.18923) (xy -0.17907 -0.18034) (xy -0.18669 -0.17145) (xy -0.19177 -0.16256) (xy -0.19812 -0.15367)
						(xy -0.20828 -0.13335) (xy -0.21971 -0.10287) (xy -0.22225 -0.09271) (xy -0.22479 -0.08128) (xy -0.22606 -0.07112)
						(xy -0.2286 -0.05969) (xy -0.2286 -0.01651) (xy -0.22606 -0.00508) (xy -0.22479 0.00508) (xy -0.22225 0.01651)
						(xy -0.21971 0.02667) (xy -0.20828 0.05715) (xy -0.19812 0.07747) (xy -0.19177 0.08636) (xy -0.18669 0.09525)
						(xy -0.17907 0.10414) (xy -0.17272 0.11303) (xy -0.1651 0.12065) (xy -0.1651 0.7366) (xy -0.16256 0.76835)
						(xy -0.1524 0.8001) (xy -0.13716 0.82804) (xy -0.11684 0.85344) (xy -0.09144 0.87376) (xy -0.0635 0.889)
						(xy -0.03175 0.89916) (xy 0 0.9017) (xy 0.03175 0.89916) (xy 0.0635 0.889) (xy 0.09144 0.87376)
						(xy 0.11684 0.85344) (xy 0.13716 0.82804) (xy 0.1524 0.8001) (xy 0.16256 0.76835) (xy 0.1651 0.7366)
						(xy 0.1651 0.11938) (xy 0.17272 0.11176) (xy 0.19812 0.0762) (xy 0.2032 0.06604) (xy 0.20701 0.05715)
						(xy 0.21209 0.04699) (xy 0.2159 0.03683) (xy 0.21844 0.02667) (xy 0.22225 0.01524) (xy 0.22352 0.00508)
						(xy 0.22606 -0.00508) (xy 0.22733 -0.01651) (xy 0.22733 -0.02667) (xy 0.2286 -0.0381) (xy 0.22733 -0.04953)
						(xy 0.22733 -0.05969) (xy 0.22606 -0.07112) (xy 0.22352 -0.08128) (xy 0.22225 -0.09144) (xy 0.21844 -0.10287)
						(xy 0.2159 -0.11303) (xy 0.21209 -0.12319) (xy 0.20701 -0.13335) (xy 0.2032 -0.14224) (xy 0.19812 -0.1524)
						(xy 0.17272 -0.18796) (xy 0.1651 -0.19558) (xy 0.1651 -0.7366) (xy 0.16256 -0.76835) (xy 0.1524 -0.8001)
						(xy 0.13716 -0.82804) (xy 0.11684 -0.85344) (xy 0.09144 -0.87376) (xy 0.0635 -0.889) (xy 0.03175 -0.89916)
					)
					(width 0)
					(fill yes)
				)
			)
		)
		(pad "160" smd custom
			(at 18.450052 4.100068)
			(size 0.1143 0.1143)
			(layers "B.Cu" "B.Mask" "B.Paste")
			(net "M_A_DQ46")
			(options
				(clearance outline)
				(anchor circle)
			)
			(primitives
				(gr_poly
					(pts
						(xy 0 -0.9017) (xy -0.03175 -0.89916) (xy -0.0635 -0.889) (xy -0.09144 -0.87376) (xy -0.11684 -0.85344)
						(xy -0.13716 -0.82804) (xy -0.1524 -0.8001) (xy -0.16256 -0.76835) (xy -0.1651 -0.7366) (xy -0.1651 -0.11938)
						(xy -0.17272 -0.11176) (xy -0.19812 -0.0762) (xy -0.2032 -0.06604) (xy -0.20701 -0.05715) (xy -0.21209 -0.04699)
						(xy -0.2159 -0.03683) (xy -0.21844 -0.02667) (xy -0.22225 -0.01524) (xy -0.22352 -0.00508) (xy -0.22606 0.00508)
						(xy -0.22733 0.01651) (xy -0.22733 0.02667) (xy -0.2286 0.0381) (xy -0.22733 0.04953) (xy -0.22733 0.05969)
						(xy -0.22606 0.07112) (xy -0.22352 0.08128) (xy -0.22225 0.09144) (xy -0.21844 0.10287) (xy -0.2159 0.11303)
						(xy -0.21209 0.12319) (xy -0.20701 0.13335) (xy -0.2032 0.14224) (xy -0.19812 0.1524) (xy -0.17272 0.18796)
						(xy -0.1651 0.19558) (xy -0.1651 0.7366) (xy -0.16256 0.76835) (xy -0.1524 0.8001) (xy -0.13716 0.82804)
						(xy -0.11684 0.85344) (xy -0.09144 0.87376) (xy -0.0635 0.889) (xy -0.03175 0.89916) (xy 0 0.9017)
						(xy 0.03175 0.89916) (xy 0.0635 0.889) (xy 0.09144 0.87376) (xy 0.11684 0.85344) (xy 0.13716 0.82804)
						(xy 0.1524 0.8001) (xy 0.16256 0.76835) (xy 0.1651 0.7366) (xy 0.1651 0.19685) (xy 0.17272 0.18923)
						(xy 0.17907 0.18034) (xy 0.18669 0.17145) (xy 0.19177 0.16256) (xy 0.19812 0.15367) (xy 0.20828 0.13335)
						(xy 0.21971 0.10287) (xy 0.22225 0.09271) (xy 0.22479 0.08128) (xy 0.22606 0.07112) (xy 0.2286 0.05969)
						(xy 0.2286 0.01651) (xy 0.22606 0.00508) (xy 0.22479 -0.00508) (xy 0.22225 -0.01651) (xy 0.21971 -0.02667)
						(xy 0.20828 -0.05715) (xy 0.19812 -0.07747) (xy 0.19177 -0.08636) (xy 0.18669 -0.09525) (xy 0.17907 -0.10414)
						(xy 0.17272 -0.11303) (xy 0.1651 -0.12065) (xy 0.1651 -0.7366) (xy 0.16256 -0.76835) (xy 0.1524 -0.8001)
						(xy 0.13716 -0.82804) (xy 0.11684 -0.85344) (xy 0.09144 -0.87376) (xy 0.0635 -0.889) (xy 0.03175 -0.89916)
					)
					(width 0)
					(fill yes)
				)
			)
		)
	)
)
